FILE_TYPE = CONNECTIVITY;
{Allegro Design Entry HDL 16.6-p007 (v16-6-112F) 10/10/2012}
"PAGE_NUMBER" = 213;
0"NC";
1"P3V3_STBY\g";
2"GND\g";
3"GND\g";
4"GND\g";
5"GND\g";
6"GND\g";
7"P3V3_STBY\g";
8"PVCCIO_CPU1\g";
9"PVCCIO_CPU1\g";
10"GND\g";
11"GND\g";
12"GND\g";
13"GND\g";
14"GND\g";
15"GND\g";
16"VR_FET_SW_P12V_STBY_PVCCIN_CPU0\g";
17"VR_PVCCIO_CPU1_AVSP"VOLTAGE"1.05";
18"VSENSE_PVCCIO_CPU1_AVSN";
19"FM_PVCCIO_CPU1_EN";
20"A_TSENSE_PVCCIO_CPU1";
21"ISENSE_PVCCIO_CPU1_PH1_IMON";
22"VR_PVCCIO_CPU1_AIREF1";
23"SVID_CLK0_CPU1_R";
24"VR_PVCCIO_CPU1_XADDR1"VOLTAGE"3.3";
25"VR_PVCCIO_CPU1_XADDR2"VOLTAGE"3.3";
26"VR_PVCCIO_CPU1_VDD"VOLTAGE"3.3";
27"SVID_CLK_PVCCIO_CPU1";
28"VR_PVCCIO_CPU1_EN"VOLTAGE"3.3";
29"SVID_DIO0_CPU1_R";
30"SMB_VR_STBY_LVC3_SDA";
31"SVID_VDIO_PVCCIO_CPU1";
32"IRQ_PVCCIO_CPU1_VRHOT_N";
33"SVID_ALERT_PVCCIO_CPU1";
34"VR_PVCCIO_CPU1_PWM1"VOLTAGE"3.6";
35"PU_VR_PVCCIO_CPU1_FAULT1";
36"PWRGD_PVCCIO_CPU1_R";
37"SVID_ALERT0_CPU1_R_N";
38"VR_PVCCIO_CPU1_VD12";
39"PWRGD_PVCCIO_CPU1";
40"VSENSE_PVCCIO_CPU1_AVSP";
41"VR_PVCCIO_CPU1_VINSEN";
42"SMB_VR_STBY_LVC3_SCL";
43"VR_PVCCIO_CPU1_VD12";
44"VR_PVCCIO_CPU1_VINSEN";
%"P3V3_STBY"
"1","(1875,4725)","0","mstr_symbols","I1";
;
CDS_LIB"mstr_symbols"
SIZE"1B"
VOLTAGE"3.3V"
BODY_TYPE"PLUMBING"
HDL_POWER"P3V3_STBY";
"G\NAC"1;
%"GND"
"1","(2425,1275)","0","mstr_symbols","I10";
;
ROOM"PVCCIO_CPU1"
SIZE"1B"
CDS_LIB"mstr_symbols"
VOLTAGE"0"
BODY_TYPE"PLUMBING"
HDL_POWER"GND";
"A\NAC"2;
%"GND"
"1","(-2100,2550)","0","mstr_symbols","I100";
;
CDS_LIB"mstr_symbols"
VOLTAGE"0"
ROOM"PVCCIN_CPU0_VR"
SIZE"1B"
BODY_TYPE"PLUMBING"
HDL_POWER"GND";
"A\NAC"3;
%"CAP"
"1","(-2100,2750)","0","mstr_discrete","I101";
;
LOCATION"C4W2"
VALUE"220PF"
PART_NUMBER"A36096-050"
MATERIAL"X7R"
PACK_TYPE"0402LF"
VOLTAGE"50V"
TOLERANCE"10%"
CDS_SEC"1"
CDS_LIB"mstr_discrete"
ROOM"PVCCIN_CPU0_VR"
SEC"1"
SEC_TYPE"0402LF"
CDS_LOCATION"C4W2";
"A"
$PN"1"20;
"B"
$PN"2"3;
%"RES"
"2","(-525,1175)","0","mstr_discrete","I103";
;
PACK_TYPE"0402"
WATTAGE"1/16W"
VALUE"3.16K"
LOCATION"R4E2"
TOLERANCE"1%"
PART_NUMBER"G21796-043"
MATERIAL"CHIP"
CDS_SEC"1"
CDS_LIB"mstr_discrete"
ROOM"PVCCIN_CPU1_VR"
SEC"1"
SEC_TYPE"0402"
CDS_LOCATION"R4E2";
"A"
$PN"1"25;
"B"
$PN"2"11;
%"RES"
"2","(-850,1175)","0","mstr_discrete","I104";
;
WATTAGE"1/16W"
VALUE"3.16K"
LOCATION"R4D64"
TOLERANCE"1%"
MATERIAL"CHIP"
PACK_TYPE"0402"
PART_NUMBER"G21796-043"
CDS_SEC"1"
CDS_LIB"mstr_discrete"
ROOM"PVCCIN_CPU1_VR"
SEC"1"
SEC_TYPE"0402"
CDS_LOCATION"R4D64";
"A"
$PN"1"24;
"B"
$PN"2"11;
%"CAP_A"
"1","(-2850,4250)","0","dev_discrete","I105";
;
TOLERANCE"10%"
PART_NUMBER"A36096-030"
LOCATION"C4D40"
VALUE"0.1UF"
VOLTAGE"16V"
MATERIAL"X7R"
PACK_TYPE"0402V"
CDS_LOCATION"C4D40"
CDS_LIB"dev_discrete"
BOM_COST"SM_THERM"
ROOM"CPU_FANS"
SEC_TYPE"0402V"
SEC"1"
CDS_SEC"1";
"B"
$PN"2"14;
"A"
$PN"1"41;
%"CAP_A"
"1","(2025,1575)","0","dev_discrete","I11";
;
LOCATION"C4D32"
VALUE"0.1UF"
PART_NUMBER"A36096-030"
PACK_TYPE"0402V"
MATERIAL"X7R"
TOLERANCE"10%"
VOLTAGE"16V"
CDS_LIB"dev_discrete"
SEC"1"
SEC_TYPE"0402V"
CDS_SEC"1"
CDS_LOCATION"C4D32"
ROOM"PVCCIO_CPU1";
"B"
$PN"2"4;
"A"
$PN"1"38;
%"GND"
"1","(2025,1375)","0","mstr_symbols","I12";
;
ROOM"PVCCIO_CPU1"
CDS_LIB"mstr_symbols"
VOLTAGE"0"
SIZE"1B"
BODY_TYPE"PLUMBING"
HDL_POWER"GND";
"A\NAC"4;
%"RES"
"1","(1950,3575)","0","mstr_discrete","I13";
;
CDS_SEC"1"
PART_NUMBER"G21796-250"
LOCATION"R4D46"
VALUE"22.1"
WATTAGE"1/16W"
MATERIAL"CHIP"
TOLERANCE"1.0%"
PACK_TYPE"0402"
CDS_LIB"mstr_discrete"
ROOM"PVCCIO_CPU1"
CDS_LOCATION"R4D46"
SEC"1"
SEC_TYPE"0402";
"B"
$PN"2"39;
"A"
$PN"1"36;
%"RES"
"2","(1600,4075)","0","mstr_discrete","I14";
;
CDS_SEC"1"
CDS_LOCATION"R6P49"
LOCATION"R6P49"
VALUE"2.26K"
TOLERANCE"1.0%"
WATTAGE"1/16W"
MATERIAL"EMPTY"
PART_NUMBER"G21796-311"
PACK_TYPE"0402"
ROOM"PVCCIO_CPU1"
CDS_LIB"mstr_discrete"
SEC"1"
SEC_TYPE"0402";
"A"
$PN"1"1;
"B"
$PN"2"35;
%"RES"
"2","(950,4050)","0","mstr_discrete","I15";
;
CDS_SEC"1"
PART_NUMBER"G21796-026"
LOCATION"R4D42"
VALUE"1.00K"
PACK_TYPE"0402"
WATTAGE"1/16W"
MATERIAL"CHIP"
TOLERANCE"1%"
SEC_TYPE"0402"
SEC"1"
CDS_LIB"mstr_discrete"
ROOM"PVCCIO_CPU1"
CDS_LOCATION"R4D42";
"A"
$PN"1"1;
"B"
$PN"2"36;
%"RES"
"1","(1450,3125)","0","mstr_discrete","I16";
;
CDS_SEC"1"
PACK_TYPE"0402"
PART_NUMBER"G21497-005"
WATTAGE"1/16W"
VALUE"0.0"
TOLERANCE"5%"
LOCATION"R4D56"
MATERIAL"CHIP"
SEC_TYPE"0402"
SEC"1"
CDS_LIB"mstr_discrete"
CDS_LOCATION"R4D56"
ROOM"PVCCIO_CPU1";
"B"
$PN"2"37;
"A"
$PN"1"33;
%"CAP_A"
"1","(150,4150)","0","dev_discrete","I17";
;
CDS_SEC"1"
MATERIAL"X6S"
PART_NUMBER"D97712-004"
PACK_TYPE"0402V"
TOLERANCE"10%"
VOLTAGE"6.3V"
LOCATION"C4D36"
VALUE"1.0UF"
SEC_TYPE"0402V"
SEC"1"
CDS_LIB"dev_discrete"
CDS_LOCATION"C4D36"
ROOM"PVCCIO_CPU1";
"B"
$PN"2"5;
"A"
$PN"1"26;
%"GND"
"1","(150,3950)","0","mstr_symbols","I18";
;
ROOM"PVCCIO_CPU1"
SIZE"1B"
CDS_LIB"mstr_symbols"
VOLTAGE"0"
BODY_TYPE"PLUMBING"
HDL_POWER"GND";
"A\NAC"5;
%"GND"
"1","(1000,1875)","0","mstr_symbols","I21";
;
ROOM"PVCCIO_CPU1"
CDS_LIB"mstr_symbols"
VOLTAGE"0"
SIZE"1B"
BODY_TYPE"PLUMBING"
HDL_POWER"GND";
"A\NAC"6;
%"P3V3_STBY"
"1","(-550,4825)","0","mstr_symbols","I24";
;
VOLTAGE"3.3V"
CDS_LIB"mstr_symbols"
SIZE"1B"
BODY_TYPE"PLUMBING"
HDL_POWER"P3V3_STBY";
"G\NAC"7;
%"RES"
"2","(-550,4500)","0","mstr_discrete","I25";
;
CDS_SEC"1"
PACK_TYPE"0402"
PART_NUMBER"G21497-005"
MATERIAL"CHIP"
WATTAGE"1/16W"
TOLERANCE"5%"
VALUE"0.0"
LOCATION"R4D47"
SEC_TYPE"0402"
SEC"1"
CDS_LIB"mstr_discrete"
ROOM"PVCCIO_CPU1"
CDS_LOCATION"R4D47";
"A"
$PN"1"7;
"B"
$PN"2"26;
%"PVCCIO_CPU1"
"1","(-1450,4900)","0","mstr_symbols","I26";
;
VOLTAGE"1.1V"
CDS_LIB"mstr_symbols"
BODY_TYPE"PLUMBING"
HDL_POWER"PVCCIO_CPU1";
"G\NAC"8;
%"RES"
"2","(-1450,4475)","0","mstr_discrete","I27";
;
CDS_SEC"1"
TOLERANCE"1%"
VALUE"100.0"
LOCATION"R6P35"
PACK_TYPE"0402"
PART_NUMBER"G21796-017"
MATERIAL"EMPTY"
WATTAGE"1/16W"
SEC_TYPE"0402"
SEC"1"
CDS_LIB"mstr_discrete"
CDS_LOCATION"R6P35"
ROOM"PVCCIO_CPU1";
"A"
$PN"1"8;
"B"
$PN"2"29;
%"PVCCIO_CPU1"
"1","(-2050,4875)","0","mstr_symbols","I28";
;
CDS_LIB"mstr_symbols"
VOLTAGE"1.1V"
BODY_TYPE"PLUMBING"
HDL_POWER"PVCCIO_CPU1";
"G\NAC"9;
%"RES"
"2","(-2050,4425)","0","mstr_discrete","I30";
;
CDS_SEC"1"
PART_NUMBER"G21796-203"
PACK_TYPE"0402"
TOLERANCE"1%"
WATTAGE"1/16W"
MATERIAL"EMPTY"
VALUE"110"
LOCATION"R6P33"
CDS_LIB"mstr_discrete"
CDS_LOCATION"R6P33"
ROOM"PVCCIO_CPU1"
SEC"1"
SEC_TYPE"0402";
"A"
$PN"1"9;
"B"
$PN"2"23;
%"RES"
"2","(-2425,4700)","0","mstr_discrete","I31";
;
CDS_SEC"1"
WATTAGE"1/16W"
MATERIAL"CHIP"
PART_NUMBER"G21796-160"
PACK_TYPE"0402"
TOLERANCE"1%"
VALUE"100.0K"
LOCATION"R4D60"
CDS_LOCATION"R4D60"
CDS_LIB"mstr_discrete"
ROOM"PVCCIO_CPU1"
SEC"1"
SEC_TYPE"0402";
"A"
$PN"1"16;
"B"
$PN"2"41;
%"RES"
"2","(-2425,4250)","0","mstr_discrete","I32";
;
CDS_SEC"1"
LOCATION"R4D57"
PACK_TYPE"0402"
MATERIAL"CHIP"
TOLERANCE"1%"
VALUE"1.5K"
WATTAGE"1/16W"
PART_NUMBER"G21796-003"
CDS_LIB"mstr_discrete"
ROOM"PVCCIO_CPU1"
CDS_LOCATION"R4D57"
SEC"1"
SEC_TYPE"0402";
"A"
$PN"1"41;
"B"
$PN"2"13;
%"CAP_A"
"1","(-250,4150)","0","dev_discrete","I35";
;
CDS_SEC"1"
LOCATION"C4D38"
VALUE"0.1UF"
VOLTAGE"16V"
TOLERANCE"10%"
PART_NUMBER"A36096-030"
PACK_TYPE"0402V"
MATERIAL"X7R"
SEC_TYPE"0402V"
SEC"1"
CDS_LIB"dev_discrete"
CDS_LOCATION"C4D38"
ROOM"PVCCIO_CPU1";
"B"
$PN"2"10;
"A"
$PN"1"26;
%"GND"
"1","(-250,3950)","0","mstr_symbols","I36";
;
ROOM"PVCCIO_CPU1"
SIZE"1B"
CDS_LIB"mstr_symbols"
VOLTAGE"0"
BODY_TYPE"PLUMBING"
HDL_POWER"GND";
"A\NAC"10;
%"RES"
"1","(-1175,2925)","0","mstr_discrete","I37";
;
CDS_SEC"1"
MATERIAL"CHIP"
PACK_TYPE"0402"
TOLERANCE"5%"
LOCATION"R4D54"
PART_NUMBER"G21497-005"
WATTAGE"1/16W"
VALUE"0.0"
SEC_TYPE"0402"
SEC"1"
CDS_LIB"mstr_discrete"
CDS_LOCATION"R4D54"
ROOM"PVCCIO_CPU1";
"B"
$PN"2"31;
"A"
$PN"1"29;
%"GND"
"1","(-850,750)","0","mstr_symbols","I44";
;
ROOM"PVCCIO_CPU1"
SIZE"1B"
CDS_LIB"mstr_symbols"
VOLTAGE"0"
BODY_TYPE"PLUMBING"
HDL_POWER"GND";
"A\NAC"11;
%"GND"
"1","(-950,2025)","0","mstr_symbols","I45";
;
SIZE"1B"
CDS_LIB"mstr_symbols"
VOLTAGE"0"
ROOM"PVCCIO_CPU1"
BODY_TYPE"PLUMBING"
HDL_POWER"GND";
"A\NAC"12;
%"RES"
"1","(-1825,3925)","0","mstr_discrete","I46";
;
CDS_SEC"1"
LOCATION"R4D51"
WATTAGE"1/16W"
VALUE"150.0"
PACK_TYPE"0402"
MATERIAL"CHIP"
TOLERANCE"1%"
PART_NUMBER"G21796-009"
CDS_LIB"mstr_discrete"
ROOM"PVCCIO_CPU1"
CDS_LOCATION"R4D51"
SEC"1"
SEC_TYPE"0402";
"B"
$PN"2"27;
"A"
$PN"1"23;
%"GND"
"1","(-2425,4000)","0","mstr_symbols","I47";
;
SIZE"1B"
CDS_LIB"mstr_symbols"
VOLTAGE"0"
ROOM"PVCCIO_CPU1"
BODY_TYPE"PLUMBING"
HDL_POWER"GND";
"A\NAC"13;
%"GND"
"1","(-2850,4025)","0","mstr_symbols","I49";
;
CDS_LIB"mstr_symbols"
SIZE"1B"
VOLTAGE"0"
ROOM"PVCCIO_CPU1"
BODY_TYPE"PLUMBING"
HDL_POWER"GND";
"A\NAC"14;
%"RES"
"2","(2175,4050)","0","mstr_discrete","I63";
;
CDS_SEC"1"
PART_NUMBER"G21796-026"
WATTAGE"1/16W"
MATERIAL"CHIP"
TOLERANCE"1%"
VALUE"1.00K"
PACK_TYPE"0402"
LOCATION"R4D49"
SEC_TYPE"0402"
SEC"1"
CDS_LIB"mstr_discrete"
CDS_LOCATION"R4D49";
"A"
$PN"1"1;
"B"
$PN"2"32;
%"CAP"
"1","(1750,2700)","0","mstr_discrete","I73";
;
CDS_SEC"1"
PART_NUMBER"A36096-046"
VALUE"1000PF"
VOLTAGE"50V"
PACK_TYPE"0402LF"
LOCATION"C4D33"
TOLERANCE"10%"
MATERIAL"X7R"
CDS_LIB"mstr_discrete"
SEC_TYPE"0402LF"
SEC"1"
CDS_LOCATION"C4D33"
ROOM"PVCCIO_CPU1_VR";
"A"
$PN"1"36;
"B"
$PN"2"15;
%"GND"
"1","(1750,2500)","0","mstr_symbols","I74";
;
ROOM"PVCCIO_CPU1"
SIZE"1B"
CDS_LIB"mstr_symbols"
VOLTAGE"0"
BODY_TYPE"PLUMBING"
HDL_POWER"GND";
"A\NAC"15;
%"CAP"
"1","(-2075,1725)","0","mstr_discrete","I83";
;
CDS_SEC"1"
PART_NUMBER"A36096-050"
PACK_TYPE"0402LF"
VOLTAGE"50V"
VALUE"220PF"
TOLERANCE"10%"
LOCATION"C4D44"
MATERIAL"X7R"
CDS_LIB"mstr_discrete"
ROOM"PVCCIO_CPU1"
CDS_LOCATION"C4D44"
SEC"1"
SEC_TYPE"0402LF";
"A"
$PN"1"17;
"B"
$PN"2"18;
%"RES"
"1","(-2325,1925)","0","mstr_discrete","I84";
;
CDS_SEC"1"
LOCATION"R4E7"
MATERIAL"CHIP"
WATTAGE"1/16W"
TOLERANCE"1%"
PART_NUMBER"G21796-066"
VALUE"10.0"
PACK_TYPE"0402"
CDS_LOCATION"R4E7"
CDS_LIB"mstr_discrete"
ROOM"PVCCIO_CPU1"
SEC"1"
SEC_TYPE"0402";
"B"
$PN"2"17;
"A"
$PN"1"40;
%"CAP_A"
"1","(2425,1575)","0","dev_discrete","I9";
;
PART_NUMBER"D97712-004"
VOLTAGE"6.3V"
VALUE"1.0UF"
TOLERANCE"10%"
MATERIAL"X6S"
PACK_TYPE"0402V"
LOCATION"C4D31"
CDS_LIB"dev_discrete"
CDS_LOCATION"C4D31"
CDS_SEC"1"
ROOM"PVCCIO_CPU1"
SEC_TYPE"0402V"
SEC"1";
"B"
$PN"2"2;
"A"
$PN"1"38;
%"RES"
"1","(-1925,3225)","0","mstr_discrete","I90";
;
CDS_SEC"1"
PART_NUMBER"G21497-005"
TOLERANCE"5%"
WATTAGE"1/16W"
PACK_TYPE"0402"
MATERIAL"CHIP"
VALUE"0.0"
LOCATION"R6P41"
SEC_TYPE"0402"
SEC"1"
CDS_LOCATION"R6P41"
CDS_LIB"mstr_discrete"
ROOM"PVCCIN_CPU0_VR";
"B"
$PN"2"28;
"A"
$PN"1"19;
%"RES"
"2","(-1025,4275)","0","mstr_discrete","I91";
;
CDS_SEC"1"
PACK_TYPE"0402"
WATTAGE"1/16W"
VALUE"100.0K"
LOCATION"R6P40"
TOLERANCE"1%"
MATERIAL"EMPTY"
PART_NUMBER"G21796-010"
SEC_TYPE"0402"
SEC"1"
CDS_LIB"mstr_discrete"
ROOM"BMC"
CDS_LOCATION"R6P40"
BOM_COST"SM_CONTROLLER";
"A"
$PN"1"7;
"B"
$PN"2"28;
%"UNIVERSAL_POWER"
"1","(-2425,4975)","0","mstr_symbols","I92";
;
HDL_POWER"VR_FET_SW_P12V_STBY_PVCCIN_CPU0"
CDS_LIB"mstr_symbols";
"A"16;
%"PXE1110B"
"1","(175,2825)","0","mstr_controller","I96";
;
CDS_SEC"1"
MATERIAL"IC"
LOCATION"EU4D5"
PART_NUMBER"H89187-001"
CDS_LOCATION"EU4D5"
SEC"1"
SEC_TYPE"QFN"
PACK_TYPE"QFN"
CDS_LMAN_SYM_OUTLINE"-400,850,400,-850"
CDS_LIB"mstr_controller";
"AVRRDY"
$PN"9"36;
"PINALRT_N \B"
$PN"12"0;
"THPAD"
$PN"41"6;
"BPWM1"
$PN"3"0;
"APWM1"
$PN"5"34;
"SDA"
$PN"6"30;
"SCL"
$PN"7"42;
"VCLK"
$PN"15"27;
"VDIO"
$PN"16"31;
"RESET_N \B"
$PN"8"0;
"XADDR1"
$PN"36"24;
"XADDR2"
$PN"33"25;
"ATSEN"
$PN"35"20;
"AISEN1"
$PN"22"21;
"AIREF1"
$PN"21"22;
"VDD"
$PN"39"26;
"BTSEN"
$PN"34"0;
"BISEN1"
$PN"26"12;
"BIREF1"
$PN"25"0;
"DNC<0>"
$PN"1"0;
"DNC<1>"
$PN"2"0;
"DNC<2>"
$PN"4"0;
"DNC<4>"
$PN"28"0;
"GND<0>"
$PN"27"6;
"GND<1>"
$PN"23"6;
"VRHOT_N \B"
$PN"11"32;
"VALRT_N \B"
$PN"17"33;
"AVSEN"
$PN"19"17;
"AVREF"
$PN"20"18;
"BVSEN"
$PN"29"0;
"BVREF"
$PN"30"0;
"VINSEN"
$PN"37"44;
"IINSEN"
$PN"38"0;
"VD12"
$PN"40"43;
"DNC<3>"
$PN"24"0;
"MP0"
$PN"13"0;
"MP1"
$PN"14"0;
"MP2"
$PN"18"0;
"MP3"
$PN"31"0;
"MP4"
$PN"32"35;
"AVREN"
$PN"10"28;
%"SC22P50V2JN-4GP"
"1","(-1900,3500)","1","w_hdl","I98";
;
CDS_SEC"1"
$SEC"1"
CDS_LOCATION"CF14"
ATTRIBUTE"22PF"
TYPE"NPO"
RATED"50V"
LOCATION"CF14"
PACK_SIZE"0402"
TOLERANCE"5%"
GROUP"POWER_FAIR"
VALUE"SC22P50V2JN-4GP"
PART_NUMBER"78.22034.1FL"
PACK_TYPE"SMD-BCG"
CDS_LMAN_SYM_OUTLINE"-50,25,50,-25"
CDS_LIB"w_hdl";
"2"
$PN"2"21;
"1"
$PN"1"22;
%"RES"
"1","(-1900,3725)","0","mstr_discrete","I99";
;
CDS_SEC"1"
CDS_LOCATION"RF14"
PACK_TYPE"0402"
VALUE"1.0K"
LOCATION"RF14"
PART_NUMBER"G85996-004"
TOLERANCE"0.1%"
FAIR_SS"064.9090D.M001"
GROUP"POWER_FAIR"
WATTAGE"1/16W"
MATERIAL"CHIP"
ROOM"SB"
CDS_LIB"mstr_discrete"
SEC"1"
SEC_TYPE"0402";
"B"
$PN"2"21;
"A"
$PN"1"22;
END.
